(kicad_pcb
	(version 20260206)
	(generator "pcbnew")
	(generator_version "10.0")
	(general
		(thickness 1.6)
		(legacy_teardrops no)
	)
	(paper "A4")
	(title_block
		(title "Wiwynn_Tioga_Pass_MB.brd")
		(comment 1 "Tioga Pass / footprints 3041-3047 of 4770")
	)
	(layers
		(0 "F.Cu" signal "TOP")
		(4 "In1.Cu" signal "L2GND")
		(6 "In2.Cu" signal "L3")
		(8 "In3.Cu" signal "L4GND")
		(10 "In4.Cu" signal "L5")
		(12 "In5.Cu" signal "L6GND")
		(14 "In6.Cu" signal "L7VCC")
		(16 "In7.Cu" signal "L8VCC")
		(18 "In8.Cu" signal "L9GND")
		(20 "In9.Cu" signal "L10")
		(22 "In10.Cu" signal "L11GND")
		(24 "In11.Cu" signal "L12")
		(26 "In12.Cu" signal "L13GND")
		(2 "B.Cu" signal "BOTTOM")
		(9 "F.Adhes" user "F.Adhesive")
		(11 "B.Adhes" user "B.Adhesive")
		(13 "F.Paste" user "Package Geometry/Pastemask Top")
		(15 "B.Paste" user "Package Geometry/Pastemask Bottom")
		(5 "F.SilkS" user "Ref Des/Silkscreen Top")
		(7 "B.SilkS" user "Ref Des/Silkscreen Bottom")
		(1 "F.Mask" user "Board Geometry/Soldermask Top")
		(3 "B.Mask" user "Board Geometry/Soldermask Bottom")
		(17 "Dwgs.User" user "User.Drawings")
		(19 "Cmts.User" user "User.Comments")
		(21 "Eco1.User" user "User.Eco1")
		(23 "Eco2.User" user "User.Eco2")
		(25 "Edge.Cuts" user "Board Geometry/Outline")
		(27 "Margin" user)
		(31 "F.CrtYd" user "Package Geometry/Place Bound Top")
		(29 "B.CrtYd" user "Package Geometry/Place Bound Bottom")
		(35 "F.Fab" user "Ref Des/Assembly Top")
		(33 "B.Fab" user "Ref Des/Assembly Bottom")
	)
	(footprint ""
		(layer "B.Cu")
		(at 405.219408 -93.755718 -90)
		(property "Reference" "R2N23"
			(at 0 0 90)
			(layer "B.SilkS")
			(hide yes)
			(effects
				(font
					(size 1.27 1.27)
				)
				(justify mirror)
			)
		)
		(property "Value" ""
			(at 0 0 90)
			(layer "B.Fab")
			(effects
				(font
					(size 1.27 1.27)
				)
				(justify mirror)
			)
		)
		(duplicate_pad_numbers_are_jumpers no)
		(fp_poly
			(pts
				(xy 0.2794 -0.1016) (xy -0.2794 -0.1016) (xy -0.2794 0.9906) (xy 0.2794 0.9906)
			)
			(stroke
				(width 0)
				(type default)
			)
			(fill no)
			(layer "B.CrtYd")
		)
		(fp_line
			(start -0.2794 0.9906)
			(end -0.2794 -0.1016)
			(stroke
				(width 0.1)
				(type default)
			)
			(layer "B.Fab")
		)
		(fp_line
			(start 0.2794 0.9906)
			(end -0.2794 0.9906)
			(stroke
				(width 0.1)
				(type default)
			)
			(layer "B.Fab")
		)
		(fp_line
			(start -0.2794 -0.1016)
			(end 0.2794 -0.1016)
			(stroke
				(width 0.1)
				(type default)
			)
			(layer "B.Fab")
		)
		(fp_line
			(start 0.2794 -0.1016)
			(end 0.2794 0.9906)
			(stroke
				(width 0.1)
				(type default)
			)
			(layer "B.Fab")
		)
		(pad "1" smd rect
			(at 0 0 90)
			(size 0.508 0.508)
			(layers "B.Cu" "B.Mask" "B.Paste")
			(net "P3V3_STBY")
		)
		(pad "2" smd rect
			(at 0 0.889 90)
			(size 0.508 0.508)
			(layers "B.Cu" "B.Mask" "B.Paste")
			(net "FM_QAT_EN_N")
		)
		(zone
			(layer "B.Cu")
			(hatch none 0.5)
			(connect_pads
				(clearance 0)
			)
			(min_thickness 0.25)
			(keepout
				(tracks not_allowed)
				(vias allowed)
				(pads allowed)
				(copperpour not_allowed)
				(footprints allowed)
			)
			(placement
				(enabled no)
				(sheetname "")
			)
			(fill
				(thermal_gap 0.5)
				(thermal_bridge_width 0.5)
				(island_removal_mode 0)
			)
			(polygon
				(pts
					(xy 404.584408 -93.501718) (xy 404.584408 -94.009718) (xy 404.965408 -94.009718) (xy 404.965408 -93.501718)
				)
			)
		)
		(zone
			(layer "B.Cu")
			(hatch none 0.5)
			(connect_pads
				(clearance 0)
			)
			(min_thickness 0.25)
			(keepout
				(tracks allowed)
				(vias not_allowed)
				(pads allowed)
				(copperpour not_allowed)
				(footprints allowed)
			)
			(placement
				(enabled no)
				(sheetname "")
			)
			(fill
				(thermal_gap 0.5)
				(thermal_bridge_width 0.5)
				(island_removal_mode 0)
			)
			(polygon
				(pts
					(xy 404.965408 -93.501718) (xy 404.965408 -94.009718) (xy 404.584408 -94.009718) (xy 404.584408 -93.501718)
				)
			)
		)
	)
	(footprint ""
		(layer "B.Cu")
		(at 380.492 -131.953 -90)
		(property "Reference" "FB3M3"
			(at 0 0 90)
			(layer "B.SilkS")
			(hide yes)
			(effects
				(font
					(size 1.27 1.27)
				)
				(justify mirror)
			)
		)
		(property "Value" ""
			(at 0 0 90)
			(layer "B.Fab")
			(effects
				(font
					(size 1.27 1.27)
				)
				(justify mirror)
			)
		)
		(duplicate_pad_numbers_are_jumpers no)
		(fp_poly
			(pts
				(xy 0.15113 -0.47498) (xy -1.59893 -0.47498) (xy -1.59893 0.47498) (xy 0.15113 0.47498)
			)
			(stroke
				(width 0)
				(type default)
			)
			(fill no)
			(layer "B.CrtYd")
		)
		(fp_line
			(start -1.59893 0.47498)
			(end 0.15113 0.47498)
			(stroke
				(width 0.1)
				(type default)
			)
			(layer "B.Fab")
		)
		(fp_line
			(start 0.15113 0.47498)
			(end 0.15113 -0.47498)
			(stroke
				(width 0.1)
				(type default)
			)
			(layer "B.Fab")
		)
		(fp_line
			(start -1.59893 -0.47498)
			(end -1.59893 0.47498)
			(stroke
				(width 0.1)
				(type default)
			)
			(layer "B.Fab")
		)
		(fp_line
			(start 0.15113 -0.47498)
			(end -1.59893 -0.47498)
			(stroke
				(width 0.1)
				(type default)
			)
			(layer "B.Fab")
		)
		(pad "1" smd rect
			(at 0 0 90)
			(size 0.9398 0.9398)
			(layers "B.Cu" "B.Mask" "B.Paste")
			(net "P1V05_PCH_STBY")
		)
		(pad "2" smd rect
			(at -1.4478 0 90)
			(size 0.9398 0.9398)
			(layers "B.Cu" "B.Mask" "B.Paste")
			(net "P1V05_PCH_STBY_VCCA_XTAL")
		)
		(zone
			(layer "B.Cu")
			(hatch none 0.5)
			(connect_pads
				(clearance 0)
			)
			(min_thickness 0.25)
			(keepout
				(tracks allowed)
				(vias not_allowed)
				(pads allowed)
				(copperpour not_allowed)
				(footprints allowed)
			)
			(placement
				(enabled no)
				(sheetname "")
			)
			(fill
				(thermal_gap 0.5)
				(thermal_bridge_width 0.5)
				(island_removal_mode 0)
			)
			(polygon
				(pts
					(xy 380.0221 -132.4229) (xy 380.9619 -132.4229) (xy 380.9619 -132.9309) (xy 380.0221 -132.9309)
				)
			)
		)
	)
	(footprint ""
		(layer "B.Cu")
		(at 476.310198 -124.756926)
		(property "Reference" "CR1M2"
			(at 1.082802 -1.040384 0)
			(unlocked yes)
			(layer "B.SilkS")
			(effects
				(font
					(size 0.7874 0.5842)
					(thickness 0.1524)
				)
				(justify left mirror)
			)
		)
		(property "Value" ""
			(at 0 0 0)
			(layer "B.Fab")
			(effects
				(font
					(size 1.27 1.27)
				)
				(justify mirror)
			)
		)
		(duplicate_pad_numbers_are_jumpers no)
		(fp_circle
			(center 0.690626 -0.00254)
			(end 0.817626 -0.00254)
			(stroke
				(width 0.254)
				(type default)
			)
			(fill no)
			(layer "B.SilkS")
		)
		(fp_rect
			(start 0.225552 2.167382)
			(end -0.809498 -0.167386)
			(stroke
				(width 0)
				(type default)
			)
			(fill no)
			(layer "B.CrtYd")
		)
		(fp_line
			(start -0.809498 -0.167386)
			(end -0.809498 2.167382)
			(stroke
				(width 0.1)
				(type default)
			)
			(layer "B.Fab")
		)
		(fp_line
			(start -0.809498 2.167382)
			(end 0.225552 2.167382)
			(stroke
				(width 0.1)
				(type default)
			)
			(layer "B.Fab")
		)
		(fp_line
			(start 0.225552 -0.167386)
			(end -0.809498 -0.167386)
			(stroke
				(width 0.1)
				(type default)
			)
			(layer "B.Fab")
		)
		(fp_line
			(start 0.225552 2.167382)
			(end 0.225552 -0.167386)
			(stroke
				(width 0.1)
				(type default)
			)
			(layer "B.Fab")
		)
		(fp_circle
			(center 0.589026 -0.5334)
			(end 0.716026 -0.5334)
			(stroke
				(width 0.254)
				(type default)
			)
			(fill no)
			(layer "B.Fab")
		)
		(pad "1" smd rect
			(at 0 0 180)
			(size 0.3556 0.2032)
			(layers "B.Cu" "B.Mask" "B.Paste")
			(net "USB2_P01_ESD_DP")
		)
		(pad "2" smd rect
			(at 0 0.500126 180)
			(size 0.3556 0.2032)
			(layers "B.Cu" "B.Mask" "B.Paste")
			(net "USB2_P01_ESD_DN")
		)
		(pad "3" smd rect
			(at -0.2921 0.999998 180)
			(size 0.9398 0.4064)
			(layers "B.Cu" "B.Mask" "B.Paste")
			(net "GND")
		)
		(pad "4" smd rect
			(at 0 1.500124 180)
			(size 0.3556 0.2032)
			(layers "B.Cu" "B.Mask" "B.Paste")
			(net "TP_USB_ESD_AC2")
		)
		(pad "5" smd rect
			(at 0 1.999996 180)
			(size 0.3556 0.2032)
			(layers "B.Cu" "B.Mask" "B.Paste")
			(net "TP_USB_ESD_AC3")
		)
		(pad "6" smd rect
			(at -0.583946 1.999996 180)
			(size 0.3556 0.2032)
			(layers "B.Cu" "B.Mask" "B.Paste")
			(net "TP_USB_ESD_OUT3")
		)
		(pad "7" smd rect
			(at -0.583946 1.500124 180)
			(size 0.3556 0.2032)
			(layers "B.Cu" "B.Mask" "B.Paste")
			(net "TP_USB_ESD_OUT2")
		)
		(pad "8" smd rect
			(at -0.583946 0.500126 180)
			(size 0.3556 0.2032)
			(layers "B.Cu" "B.Mask" "B.Paste")
			(net "USB2_P01_ESD_DN")
		)
		(pad "9" smd rect
			(at -0.583946 0 180)
			(size 0.3556 0.2032)
			(layers "B.Cu" "B.Mask" "B.Paste")
			(net "USB2_P01_ESD_DP")
		)
	)
	(footprint ""
		(layer "B.Cu")
		(at 492.540798 -26.257758 90)
		(property "Reference" "C1R25"
			(at 0.8382 -0.67818 90)
			(unlocked yes)
			(layer "B.SilkS")
			(effects
				(font
					(size 0.4064 0.254)
					(thickness 0.1524)
				)
				(justify left mirror)
			)
		)
		(property "Value" ""
			(at 0 0 90)
			(layer "B.Fab")
			(effects
				(font
					(size 1.27 1.27)
				)
				(justify mirror)
			)
		)
		(duplicate_pad_numbers_are_jumpers no)
		(fp_poly
			(pts
				(xy -0.3048 -0.1016) (xy -0.3048 0.9906) (xy 0.3048 0.9906) (xy 0.3048 -0.1016)
			)
			(stroke
				(width 0)
				(type default)
			)
			(fill no)
			(layer "B.CrtYd")
		)
		(fp_line
			(start 0.3048 -0.1016)
			(end 0.3048 0.9906)
			(stroke
				(width 0.1)
				(type default)
			)
			(layer "B.Fab")
		)
		(fp_line
			(start -0.3048 -0.1016)
			(end 0.3048 -0.1016)
			(stroke
				(width 0.1)
				(type default)
			)
			(layer "B.Fab")
		)
		(fp_line
			(start 0.3048 0.9906)
			(end -0.3048 0.9906)
			(stroke
				(width 0.1)
				(type default)
			)
			(layer "B.Fab")
		)
		(fp_line
			(start -0.3048 0.9906)
			(end -0.3048 -0.1016)
			(stroke
				(width 0.1)
				(type default)
			)
			(layer "B.Fab")
		)
		(pad "1" smd rect
			(at 0 0 270)
			(size 0.508 0.508)
			(layers "B.Cu" "B.Mask" "B.Paste")
			(net "P3V3_STBY")
		)
		(pad "2" smd rect
			(at 0 0.889 270)
			(size 0.508 0.508)
			(layers "B.Cu" "B.Mask" "B.Paste")
			(net "GND")
		)
		(zone
			(layer "B.Cu")
			(hatch none 0.5)
			(connect_pads
				(clearance 0)
			)
			(min_thickness 0.25)
			(keepout
				(tracks allowed)
				(vias not_allowed)
				(pads allowed)
				(copperpour not_allowed)
				(footprints allowed)
			)
			(placement
				(enabled no)
				(sheetname "")
			)
			(fill
				(thermal_gap 0.5)
				(thermal_bridge_width 0.5)
				(island_removal_mode 0)
			)
			(polygon
				(pts
					(xy 492.794798 -26.511758) (xy 492.794798 -26.003758) (xy 493.175798 -26.003758) (xy 493.175798 -26.511758)
				)
			)
		)
		(zone
			(layer "B.Cu")
			(hatch none 0.5)
			(connect_pads
				(clearance 0)
			)
			(min_thickness 0.25)
			(keepout
				(tracks not_allowed)
				(vias allowed)
				(pads allowed)
				(copperpour not_allowed)
				(footprints allowed)
			)
			(placement
				(enabled no)
				(sheetname "")
			)
			(fill
				(thermal_gap 0.5)
				(thermal_bridge_width 0.5)
				(island_removal_mode 0)
			)
			(polygon
				(pts
					(xy 493.175798 -26.511758) (xy 493.175798 -26.003758) (xy 492.794798 -26.003758) (xy 492.794798 -26.511758)
				)
			)
		)
	)
	(footprint ""
		(layer "B.Cu")
		(at 39.031164 -35.658552 180)
		(property "Reference" "C9T3"
			(at -3.10007 3.24612 270)
			(unlocked yes)
			(layer "B.SilkS")
			(effects
				(font
					(size 0.7874 0.5842)
					(thickness 0.1524)
				)
				(justify mirror)
			)
		)
		(property "Value" ""
			(at 0 0 0)
			(layer "B.Fab")
			(effects
				(font
					(size 1.27 1.27)
				)
				(justify mirror)
			)
		)
		(duplicate_pad_numbers_are_jumpers no)
		(fp_line
			(start 2.563114 1.633728)
			(end 1.6002 1.633728)
			(stroke
				(width 0.1524)
				(type default)
			)
			(layer "B.SilkS")
		)
		(fp_line
			(start 2.563114 -1.616456)
			(end 2.563114 1.633728)
			(stroke
				(width 0.1524)
				(type default)
			)
			(layer "B.SilkS")
		)
		(fp_line
			(start 2.286 7.366)
			(end 2.286 1.632712)
			(stroke
				(width 0.1524)
				(type default)
			)
			(layer "B.SilkS")
		)
		(fp_line
			(start 2.286 7.366)
			(end 1.60147 7.366)
			(stroke
				(width 0.1524)
				(type default)
			)
			(layer "B.SilkS")
		)
		(fp_line
			(start 1.6002 -1.616456)
			(end 2.563114 -1.616456)
			(stroke
				(width 0.1524)
				(type default)
			)
			(layer "B.SilkS")
		)
		(fp_line
			(start -1.6002 -1.616456)
			(end -2.504948 -1.616456)
			(stroke
				(width 0.1524)
				(type default)
			)
			(layer "B.SilkS")
		)
		(fp_line
			(start -2.286 7.366)
			(end -1.600708 7.366)
			(stroke
				(width 0.1524)
				(type default)
			)
			(layer "B.SilkS")
		)
		(fp_line
			(start -2.286 7.366)
			(end -2.286 1.63195)
			(stroke
				(width 0.1524)
				(type default)
			)
			(layer "B.SilkS")
		)
		(fp_line
			(start -2.504948 1.633728)
			(end -1.6002 1.633728)
			(stroke
				(width 0.1524)
				(type default)
			)
			(layer "B.SilkS")
		)
		(fp_line
			(start -2.504948 -1.616456)
			(end -2.504948 1.633728)
			(stroke
				(width 0.1524)
				(type default)
			)
			(layer "B.SilkS")
		)
		(fp_rect
			(start 2.286 7.366)
			(end -2.286 -0.254)
			(stroke
				(width 0)
				(type default)
			)
			(fill no)
			(layer "B.CrtYd")
		)
		(fp_line
			(start 2.286 7.366)
			(end 2.286 -0.254)
			(stroke
				(width 0.1)
				(type default)
			)
			(layer "B.Fab")
		)
		(fp_line
			(start 2.286 -0.254)
			(end -2.286 -0.254)
			(stroke
				(width 0.1)
				(type default)
			)
			(layer "B.Fab")
		)
		(fp_line
			(start -2.286 7.366)
			(end 2.286 7.366)
			(stroke
				(width 0.1)
				(type default)
			)
			(layer "B.Fab")
		)
		(fp_line
			(start -2.286 -0.254)
			(end -2.286 7.366)
			(stroke
				(width 0.1)
				(type default)
			)
			(layer "B.Fab")
		)
		(pad "1" smd rect
			(at 0 0)
			(size 2.54 3.048)
			(layers "B.Cu" "B.Mask" "B.Paste")
			(net "P12V_STBY")
		)
		(pad "2" smd rect
			(at 0 7.112)
			(size 2.54 3.048)
			(layers "B.Cu" "B.Mask" "B.Paste")
			(net "GND")
		)
	)
	(footprint ""
		(layer "B.Cu")
		(at 472.354402 -38.340792 -90)
		(property "Reference" "R1T9"
			(at 0 0 90)
			(layer "B.SilkS")
			(hide yes)
			(effects
				(font
					(size 1.27 1.27)
				)
				(justify mirror)
			)
		)
		(property "Value" ""
			(at 0 0 90)
			(layer "B.Fab")
			(effects
				(font
					(size 1.27 1.27)
				)
				(justify mirror)
			)
		)
		(duplicate_pad_numbers_are_jumpers no)
		(fp_poly
			(pts
				(xy 0.2794 -0.1016) (xy -0.2794 -0.1016) (xy -0.2794 0.9906) (xy 0.2794 0.9906)
			)
			(stroke
				(width 0)
				(type default)
			)
			(fill no)
			(layer "B.CrtYd")
		)
		(fp_line
			(start -0.2794 0.9906)
			(end -0.2794 -0.1016)
			(stroke
				(width 0.1)
				(type default)
			)
			(layer "B.Fab")
		)
		(fp_line
			(start 0.2794 0.9906)
			(end -0.2794 0.9906)
			(stroke
				(width 0.1)
				(type default)
			)
			(layer "B.Fab")
		)
		(fp_line
			(start -0.2794 -0.1016)
			(end 0.2794 -0.1016)
			(stroke
				(width 0.1)
				(type default)
			)
			(layer "B.Fab")
		)
		(fp_line
			(start 0.2794 -0.1016)
			(end 0.2794 0.9906)
			(stroke
				(width 0.1)
				(type default)
			)
			(layer "B.Fab")
		)
		(pad "1" smd rect
			(at 0 0 90)
			(size 0.508 0.508)
			(layers "B.Cu" "B.Mask" "B.Paste")
			(net "PWRGD_P1V2_BMC_STBY_R")
		)
		(pad "2" smd rect
			(at 0 0.889 90)
			(size 0.508 0.508)
			(layers "B.Cu" "B.Mask" "B.Paste")
			(net "PWRGD_P1V2_BMC_STBY")
		)
		(zone
			(layer "B.Cu")
			(hatch none 0.5)
			(connect_pads
				(clearance 0)
			)
			(min_thickness 0.25)
			(keepout
				(tracks not_allowed)
				(vias allowed)
				(pads allowed)
				(copperpour not_allowed)
				(footprints allowed)
			)
			(placement
				(enabled no)
				(sheetname "")
			)
			(fill
				(thermal_gap 0.5)
				(thermal_bridge_width 0.5)
				(island_removal_mode 0)
			)
			(polygon
				(pts
					(xy 471.719402 -38.086792) (xy 471.719402 -38.594792) (xy 472.100402 -38.594792) (xy 472.100402 -38.086792)
				)
			)
		)
		(zone
			(layer "B.Cu")
			(hatch none 0.5)
			(connect_pads
				(clearance 0)
			)
			(min_thickness 0.25)
			(keepout
				(tracks allowed)
				(vias not_allowed)
				(pads allowed)
				(copperpour not_allowed)
				(footprints allowed)
			)
			(placement
				(enabled no)
				(sheetname "")
			)
			(fill
				(thermal_gap 0.5)
				(thermal_bridge_width 0.5)
				(island_removal_mode 0)
			)
			(polygon
				(pts
					(xy 472.100402 -38.086792) (xy 472.100402 -38.594792) (xy 471.719402 -38.594792) (xy 471.719402 -38.086792)
				)
			)
		)
	)
	(footprint ""
		(layer "B.Cu")
		(at 481.321872 -56.090058 90)
		(property "Reference" "U8E4"
			(at -0.183896 1.760982 180)
			(unlocked yes)
			(layer "B.SilkS")
			(effects
				(font
					(size 0.7874 0.5842)
					(thickness 0.1524)
				)
				(justify left mirror)
			)
		)
		(property "Value" ""
			(at 0 0 90)
			(layer "B.Fab")
			(effects
				(font
					(size 1.27 1.27)
				)
				(justify mirror)
			)
		)
		(duplicate_pad_numbers_are_jumpers no)
		(fp_circle
			(center 0.4699 -0.8382)
			(end 0.4699 -0.7112)
			(stroke
				(width 0.254)
				(type default)
			)
			(fill no)
			(layer "B.SilkS")
		)
		(fp_poly
			(pts
				(xy -0.21463 -0.450088) (xy -1.56337 -0.450088) (xy -1.56337 1.75006) (xy -0.21463 1.75006)
			)
			(stroke
				(width 0)
				(type default)
			)
			(fill no)
			(layer "B.CrtYd")
		)
		(fp_line
			(start -0.21463 -0.450088)
			(end -1.56337 -0.450088)
			(stroke
				(width 0.1)
				(type default)
			)
			(layer "B.Fab")
		)
		(fp_line
			(start -1.56337 -0.450088)
			(end -1.56337 1.75006)
			(stroke
				(width 0.1)
				(type default)
			)
			(layer "B.Fab")
		)
		(fp_line
			(start -0.21463 1.75006)
			(end -0.21463 -0.450088)
			(stroke
				(width 0.1)
				(type default)
			)
			(layer "B.Fab")
		)
		(fp_line
			(start -1.56337 1.75006)
			(end -0.21463 1.75006)
			(stroke
				(width 0.1)
				(type default)
			)
			(layer "B.Fab")
		)
		(fp_circle
			(center 0.4699 -0.8382)
			(end 0.4699 -0.7112)
			(stroke
				(width 0.254)
				(type default)
			)
			(fill no)
			(layer "B.Fab")
		)
		(pad "1" smd rect
			(at 0 0 270)
			(size 1.016 0.381)
			(layers "B.Cu" "B.Mask" "B.Paste")
			(net "PU_TRI_STATE_EN")
		)
		(pad "2" smd rect
			(at 0 0.649986 270)
			(size 1.016 0.381)
			(layers "B.Cu" "B.Mask" "B.Paste")
			(net "FM_ALL_WAKE_N")
		)
		(pad "3" smd rect
			(at 0 1.299972 270)
			(size 1.016 0.381)
			(layers "B.Cu" "B.Mask" "B.Paste")
			(net "GND")
		)
		(pad "4" smd rect
			(at -1.778 1.299972 270)
			(size 1.016 0.381)
			(layers "B.Cu" "B.Mask" "B.Paste")
			(net "IRQ_LVC3_WAKE_R_N")
		)
		(pad "5" smd rect
			(at -1.778 0 270)
			(size 1.016 0.381)
			(layers "B.Cu" "B.Mask" "B.Paste")
			(net "P3V3_STBY")
		)
	)
)
